# T6G (Grand Teton) — schematic netlist excerpt (pin names and nets, part order shuffled) for the footprints in the layout excerpt that follows; sources: Cadence DE-HDL packaged netlist, KiCad conversion of 04192023_DAF0TMB3IC0_F0TG_MB_C_brd_V02_OCP.brd

PC583  Q_CAP  0.1UF 25V 10% X7R  pkg 0402  page 198 : A = P12V_AUX ; B = GND

DB7  TDR_3P  EMPTY  pkg TH2  page 260
  GND  = T1_GND
  IO1  = TDR_SE_50_OHM_TOP
  IO2  = TDR_SE_50_OHM_TOP

(kicad_pcb
	(version 20260206)
	(generator "pcbnew")
	(generator_version "10.0")
	(general
		(thickness 1.6)
		(legacy_teardrops no)
	)
	(paper "A4")
	(title_block
		(title "04192023_DAF0TMB3IC0_F0TG_MB_C_brd_V02_OCP.brd")
		(comment 1 "Grand Teton / footprints 620-621 of 8354")
	)
	(layers
		(0 "F.Cu" signal "TOP")
		(4 "In1.Cu" signal "GND")
		(6 "In2.Cu" signal "IN1")
		(8 "In3.Cu" signal "GND1")
		(10 "In4.Cu" signal "IN2")
		(12 "In5.Cu" signal "GND2")
		(14 "In6.Cu" signal "IN3")
		(16 "In7.Cu" signal "GND3")
		(18 "In8.Cu" signal "VCC")
		(20 "In9.Cu" signal "VCC1")
		(22 "In10.Cu" signal "GND4")
		(24 "In11.Cu" signal "IN4")
		(26 "In12.Cu" signal "GND5")
		(28 "In13.Cu" signal "IN5")
		(30 "In14.Cu" signal "GND6")
		(32 "In15.Cu" signal "IN6")
		(34 "In16.Cu" signal "GND7")
		(2 "B.Cu" signal "BOTTOM")
		(9 "F.Adhes" user "F.Adhesive")
		(11 "B.Adhes" user "B.Adhesive")
		(13 "F.Paste" user "Package Geometry/Pastemask Top")
		(15 "B.Paste" user "Package Geometry/Pastemask Bottom")
		(5 "F.SilkS" user "Ref Des/Silkscreen Top")
		(7 "B.SilkS" user "Ref Des/Silkscreen Bottom")
		(1 "F.Mask" user "Board Geometry/Soldermask Top")
		(3 "B.Mask" user "Board Geometry/Soldermask Bottom")
		(17 "Dwgs.User" user "User.Drawings")
		(19 "Cmts.User" user "User.Comments")
		(21 "Eco1.User" user "User.Eco1")
		(23 "Eco2.User" user "User.Eco2")
		(25 "Edge.Cuts" user "Board Geometry/Outline")
		(27 "Margin" user)
		(31 "F.CrtYd" user "Package Geometry/Place Bound Top")
		(29 "B.CrtYd" user "Package Geometry/Place Bound Bottom")
		(35 "F.Fab" user "Ref Des/Assembly Top")
		(33 "B.Fab" user "Ref Des/Assembly Bottom")
	)
	(footprint ""
		(layer "F.Cu")
		(at 473.635324 -437.43753 180)
		(property "Reference" "DB7"
			(at 3.42519 1.965452 0)
			(unlocked yes)
			(layer "F.SilkS")
			(effects
				(font
					(size 0.7874 0.5842)
					(thickness 0.1524)
				)
				(justify left)
			)
		)
		(property "Value" ""
			(at 0 0 180)
			(layer "F.Fab")
			(effects
				(font
					(size 1.27 1.27)
				)
			)
		)
		(duplicate_pad_numbers_are_jumpers no)
		(fp_line
			(start 3.330702 -4.771136)
			(end 0 4.011168)
			(stroke
				(width 0.1524)
				(type default)
			)
			(layer "F.SilkS")
		)
		(fp_line
			(start 0 4.011168)
			(end -3.330702 -4.771136)
			(stroke
				(width 0.1524)
				(type default)
			)
			(layer "F.SilkS")
		)
		(fp_line
			(start -3.330702 -4.771136)
			(end 3.330702 -4.771136)
			(stroke
				(width 0.1524)
				(type default)
			)
			(layer "F.SilkS")
		)
		(fp_line
			(start 3.330702 -4.771136)
			(end 0 4.011168)
			(stroke
				(width 0.1)
				(type default)
			)
			(layer "F.Fab")
		)
		(fp_line
			(start 0 4.011168)
			(end -3.330702 -4.771136)
			(stroke
				(width 0.1)
				(type default)
			)
			(layer "F.Fab")
		)
		(fp_line
			(start -3.330702 -4.771136)
			(end 3.330702 -4.771136)
			(stroke
				(width 0.1)
				(type default)
			)
			(layer "F.Fab")
		)
		(pad "1" thru_hole circle
			(at 0 0 180)
			(size 2.159 2.159)
			(drill 1.7018)
			(layers "*.Cu" "*.Mask")
			(remove_unused_layers no)
			(net "T1_GND")
			(clearance 0.0254)
			(thermal_gap 0.0254)
		)
		(pad "2" thru_hole circle
			(at -1.27 -3.348736 180)
			(size 2.159 2.159)
			(drill 1.7018)
			(layers "*.Cu" "*.Mask")
			(remove_unused_layers no)
			(net "TDR_SE_50_OHM_TOP")
			(clearance 0.0254)
			(thermal_gap 0.0254)
		)
		(pad "3" thru_hole circle
			(at 1.27 -3.348736 180)
			(size 2.159 2.159)
			(drill 1.7018)
			(layers "*.Cu" "*.Mask")
			(remove_unused_layers no)
			(net "TDR_SE_50_OHM_TOP")
			(clearance 0.0254)
			(thermal_gap 0.0254)
		)
	)
	(footprint ""
		(layer "F.Cu")
		(at 378.85624 -151.393398 -90)
		(property "Reference" "PC583"
			(at 0 0 270)
			(layer "F.SilkS")
			(hide yes)
			(effects
				(font
					(size 1.27 1.27)
				)
			)
		)
		(property "Value" ""
			(at 0 0 270)
			(layer "F.Fab")
			(effects
				(font
					(size 1.27 1.27)
				)
			)
		)
		(duplicate_pad_numbers_are_jumpers no)
		(fp_line
			(start -0.7874 0.4064)
			(end -0.7874 -0.4064)
			(stroke
				(width 0.1524)
				(type default)
			)
			(layer "F.SilkS")
		)
		(fp_line
			(start 0.7874 0.4064)
			(end -0.7874 0.4064)
			(stroke
				(width 0.1524)
				(type default)
			)
			(layer "F.SilkS")
		)
		(fp_line
			(start -0.7874 -0.4064)
			(end 0.7874 -0.4064)
			(stroke
				(width 0.1524)
				(type default)
			)
			(layer "F.SilkS")
		)
		(fp_line
			(start 0.7874 -0.4064)
			(end 0.7874 0.4064)
			(stroke
				(width 0.1524)
				(type default)
			)
			(layer "F.SilkS")
		)
		(fp_line
			(start -0.67945 0.3048)
			(end -0.67945 -0.305054)
			(stroke
				(width 0.1)
				(type default)
			)
			(layer "F.Fab")
		)
		(fp_line
			(start -0.12065 0.3048)
			(end -0.67945 0.3048)
			(stroke
				(width 0.1)
				(type default)
			)
			(layer "F.Fab")
		)
		(fp_line
			(start 0.120396 0.3048)
			(end 0.120396 0.2794)
			(stroke
				(width 0.1)
				(type default)
			)
			(layer "F.Fab")
		)
		(fp_line
			(start 0.67945 0.3048)
			(end 0.120396 0.3048)
			(stroke
				(width 0.1)
				(type default)
			)
			(layer "F.Fab")
		)
		(fp_line
			(start -0.12065 0.2794)
			(end -0.12065 0.3048)
			(stroke
				(width 0.1)
				(type default)
			)
			(layer "F.Fab")
		)
		(fp_line
			(start 0.120396 0.2794)
			(end -0.12065 0.2794)
			(stroke
				(width 0.1)
				(type default)
			)
			(layer "F.Fab")
		)
		(fp_line
			(start -0.12065 -0.2794)
			(end 0.12065 -0.2794)
			(stroke
				(width 0.1)
				(type default)
			)
			(layer "F.Fab")
		)
		(fp_line
			(start 0.12065 -0.2794)
			(end 0.12065 -0.3048)
			(stroke
				(width 0.1)
				(type default)
			)
			(layer "F.Fab")
		)
		(fp_line
			(start 0.12065 -0.3048)
			(end 0.67945 -0.3048)
			(stroke
				(width 0.1)
				(type default)
			)
			(layer "F.Fab")
		)
		(fp_line
			(start 0.67945 -0.3048)
			(end 0.67945 0.3048)
			(stroke
				(width 0.1)
				(type default)
			)
			(layer "F.Fab")
		)
		(fp_line
			(start -0.67945 -0.305054)
			(end -0.12065 -0.305054)
			(stroke
				(width 0.1)
				(type default)
			)
			(layer "F.Fab")
		)
		(fp_line
			(start -0.12065 -0.305054)
			(end -0.12065 -0.2794)
			(stroke
				(width 0.1)
				(type default)
			)
			(layer "F.Fab")
		)
		(pad "1" smd circle
			(at -0.40005 0 270)
			(size 0 0)
			(layers "F.Cu" "F.Mask" "F.Paste")
			(net "P12V_AUX")
		)
		(pad "2" smd circle
			(at 0.40005 0 270)
			(size 0 0)
			(layers "F.Cu" "F.Mask" "F.Paste")
			(net "GND")
		)
	)
)
